(kicad_pcb
	(version 20260206)
	(generator "pcbnew")
	(generator_version "10.0")
	(general
		(thickness 1.6)
		(legacy_teardrops no)
	)
	(paper "A4")
	(title_block
		(title "Bryce Canyon_R.DPB_16317-1_OCP.brd")
		(comment 1 "Bryce Canyon / footprints 87-93 of 2099")
	)
	(layers
		(0 "F.Cu" signal "TOP")
		(4 "In1.Cu" signal "L2GND")
		(6 "In2.Cu" signal "L3")
		(8 "In3.Cu" signal "L4VCC")
		(10 "In4.Cu" signal "L5VCC")
		(12 "In5.Cu" signal "L6")
		(14 "In6.Cu" signal "L7GND")
		(2 "B.Cu" signal "BOTTOM")
		(9 "F.Adhes" user "F.Adhesive")
		(11 "B.Adhes" user "B.Adhesive")
		(13 "F.Paste" user "Package Geometry/Pastemask Top")
		(15 "B.Paste" user "Package Geometry/Pastemask Bottom")
		(5 "F.SilkS" user "Ref Des/Silkscreen Top")
		(7 "B.SilkS" user "Ref Des/Silkscreen Bottom")
		(1 "F.Mask" user "Board Geometry/Soldermask Top")
		(3 "B.Mask" user "Board Geometry/Soldermask Bottom")
		(17 "Dwgs.User" user "User.Drawings")
		(19 "Cmts.User" user "User.Comments")
		(21 "Eco1.User" user "User.Eco1")
		(23 "Eco2.User" user "User.Eco2")
		(25 "Edge.Cuts" user "Board Geometry/Outline")
		(27 "Margin" user)
		(31 "F.CrtYd" user "Package Geometry/Place Bound Top")
		(29 "B.CrtYd" user "Package Geometry/Place Bound Bottom")
		(35 "F.Fab" user "Ref Des/Assembly Top")
		(33 "B.Fab" user "Ref Des/Assembly Bottom")
	)
	(footprint ""
		(layer "F.Cu")
		(at 22.967696 -372.3259 -90)
		(property "Reference" "R962"
			(at 0 0 270)
			(layer "F.SilkS")
			(hide yes)
			(effects
				(font
					(size 1.27 1.27)
				)
			)
		)
		(property "Value" "1KR5F-1-GP"
			(at 0 -8.9535 270)
			(unlocked yes)
			(layer "F.Fab")
			(hide yes)
			(effects
				(font
					(size 1.27 1.016)
					(thickness 0.1524)
				)
			)
		)
		(property "Device Type" "R805H24"
			(at 0 -10.6299 270)
			(unlocked yes)
			(layer "F.Fab")
			(hide yes)
			(effects
				(font
					(size 1.27 1.016)
					(thickness 0.1524)
				)
			)
		)
		(duplicate_pad_numbers_are_jumpers no)
		(fp_line
			(start -0.889 1.7018)
			(end 0.889 1.7018)
			(stroke
				(width 0.1524)
				(type default)
			)
			(layer "F.SilkS")
		)
		(fp_line
			(start 0.889 1.7018)
			(end 0.889 -0.508)
			(stroke
				(width 0.1524)
				(type default)
			)
			(layer "F.SilkS")
		)
		(fp_line
			(start -0.889 0.0762)
			(end -0.889 1.7018)
			(stroke
				(width 0.1524)
				(type default)
			)
			(layer "F.SilkS")
		)
		(fp_line
			(start -0.889 -1.7018)
			(end -0.889 0.2794)
			(stroke
				(width 0.1524)
				(type default)
			)
			(layer "F.SilkS")
		)
		(fp_line
			(start 0.889 -1.7018)
			(end 0.889 -0.381)
			(stroke
				(width 0.1524)
				(type default)
			)
			(layer "F.SilkS")
		)
		(fp_line
			(start 0.889 -1.7018)
			(end -0.889 -1.7018)
			(stroke
				(width 0.1524)
				(type default)
			)
			(layer "F.SilkS")
		)
		(fp_poly
			(pts
				(xy 0.9652 -1.778) (xy 0.9652 1.778) (xy -0.9652 1.778) (xy -0.9652 -1.778)
			)
			(stroke
				(width 0)
				(type default)
			)
			(fill no)
			(layer "F.CrtYd")
		)
		(fp_rect
			(start -0.9652 1.778)
			(end 0.9652 -1.778)
			(stroke
				(width 0)
				(type default)
			)
			(fill no)
			(layer "F.Fab")
		)
		(pad "1" smd rect
			(at 0 -0.9652 270)
			(size 1.397 1.143)
			(layers "F.Cu" "F.Mask" "F.Paste")
			(net "FAN_YELLOW_0")
		)
		(pad "2" smd rect
			(at 0 0.9652 270)
			(size 1.397 1.143)
			(layers "F.Cu" "F.Mask" "F.Paste")
			(net "FAN_LED_YELLOW_0")
		)
	)
	(footprint ""
		(layer "F.Cu")
		(at 476.9866 -134.7724 -90)
		(property "Reference" "R599"
			(at 0 0 270)
			(layer "F.SilkS")
			(hide yes)
			(effects
				(font
					(size 1.27 1.27)
				)
			)
		)
		(property "Value" "10KR2F-2-GP"
			(at 0.064008 -3.993896 270)
			(unlocked yes)
			(layer "F.Fab")
			(hide yes)
			(effects
				(font
					(size 1.016 1.016)
					(thickness 0.1524)
				)
			)
		)
		(property "Device Type" "R402H16"
			(at 0.064008 -5.517896 270)
			(unlocked yes)
			(layer "F.Fab")
			(hide yes)
			(effects
				(font
					(size 1.016 1.016)
					(thickness 0.1524)
				)
			)
		)
		(duplicate_pad_numbers_are_jumpers no)
		(fp_line
			(start -0.508 -0.9398)
			(end -0.508 0.9398)
			(stroke
				(width 0.1524)
				(type default)
			)
			(layer "F.SilkS")
		)
		(fp_line
			(start 0.508 -0.9398)
			(end -0.508 -0.9398)
			(stroke
				(width 0.1524)
				(type default)
			)
			(layer "F.SilkS")
		)
		(fp_rect
			(start -0.508 0.9398)
			(end 0.508 -0.9398)
			(stroke
				(width 0)
				(type default)
			)
			(fill no)
			(layer "F.CrtYd")
		)
		(fp_rect
			(start -0.508 0.9398)
			(end 0.508 -0.9398)
			(stroke
				(width 0)
				(type default)
			)
			(fill no)
			(layer "F.Fab")
		)
		(pad "1" smd custom
			(at 0 -0.4445 270)
			(size 0.1397 0.1397)
			(layers "F.Cu" "F.Mask" "F.Paste")
			(net "P3V3_STBY_B")
			(options
				(clearance outline)
				(anchor circle)
			)
			(primitives
				(gr_poly
					(pts
						(arc
							(start -0.1778 -0.2794)
							(mid -0.249642 -0.249642)
							(end -0.2794 -0.1778)
						)
						(arc
							(start -0.2794 0.1778)
							(mid -0.249642 0.249642)
							(end -0.1778 0.2794)
						)
						(arc
							(start 0.1778 0.2794)
							(mid 0.249642 0.249642)
							(end 0.2794 0.1778)
						)
						(arc
							(start 0.2794 -0.1778)
							(mid 0.249642 -0.249642)
							(end 0.1778 -0.2794)
						)
					)
					(width 0)
					(fill yes)
				)
			)
		)
		(pad "2" smd custom
			(at 0 0.4445 270)
			(size 0.1397 0.1397)
			(layers "F.Cu" "F.Mask" "F.Paste")
			(net "HDD_PRSNT_23")
			(options
				(clearance outline)
				(anchor circle)
			)
			(primitives
				(gr_poly
					(pts
						(arc
							(start -0.1778 -0.2794)
							(mid -0.249642 -0.249642)
							(end -0.2794 -0.1778)
						)
						(arc
							(start -0.2794 0.1778)
							(mid -0.249642 0.249642)
							(end -0.1778 0.2794)
						)
						(arc
							(start 0.1778 0.2794)
							(mid 0.249642 0.249642)
							(end 0.2794 0.1778)
						)
						(arc
							(start 0.2794 -0.1778)
							(mid 0.249642 -0.249642)
							(end 0.1778 -0.2794)
						)
					)
					(width 0)
					(fill yes)
				)
			)
		)
	)
	(footprint ""
		(layer "F.Cu")
		(at 371.293644 -214.860378 90)
		(property "Reference" "Q251"
			(at 0 0 90)
			(layer "F.SilkS")
			(hide yes)
			(effects
				(font
					(size 1.27 1.27)
				)
			)
		)
		(property "Value" "SSM3K324R-GP"
			(at 0.127 -8.9662 90)
			(unlocked yes)
			(layer "F.Fab")
			(hide yes)
			(effects
				(font
					(size 1.016 1.016)
					(thickness 0.1524)
				)
			)
		)
		(property "Device Type" "SOT23DGS2D4H35"
			(at 0.127 -10.4902 90)
			(unlocked yes)
			(layer "F.Fab")
			(hide yes)
			(effects
				(font
					(size 1.016 1.016)
					(thickness 0.1524)
				)
			)
		)
		(duplicate_pad_numbers_are_jumpers no)
		(fp_line
			(start 1.651 -1.778)
			(end -1.651 -1.778)
			(stroke
				(width 0.1524)
				(type default)
			)
			(layer "F.SilkS")
		)
		(fp_line
			(start -1.651 -1.778)
			(end -1.651 1.778)
			(stroke
				(width 0.1524)
				(type default)
			)
			(layer "F.SilkS")
		)
		(fp_line
			(start 1.651 1.778)
			(end 1.651 -1.778)
			(stroke
				(width 0.1524)
				(type default)
			)
			(layer "F.SilkS")
		)
		(fp_line
			(start -1.651 1.778)
			(end 1.651 1.778)
			(stroke
				(width 0.1524)
				(type default)
			)
			(layer "F.SilkS")
		)
		(fp_poly
			(pts
				(xy -1.778 1.8796) (xy -1.778 -1.8796) (xy 1.778 -1.8796) (xy 1.778 1.8796)
			)
			(stroke
				(width 0)
				(type default)
			)
			(fill no)
			(layer "F.CrtYd")
		)
		(fp_poly
			(pts
				(xy -1.778 1.8796) (xy -1.778 -1.8796) (xy 1.778 -1.8796) (xy 1.778 1.8796)
			)
			(stroke
				(width 0)
				(type default)
			)
			(fill no)
			(layer "F.Fab")
		)
		(pad "D" smd custom
			(at 0 -0.9525 90)
			(size 0.1905 0.1905)
			(layers "F.Cu" "F.Mask" "F.Paste")
			(net "DRV_ACT_8_N")
			(options
				(clearance outline)
				(anchor circle)
			)
			(primitives
				(gr_poly
					(pts
						(arc
							(start -0.1778 0.5715)
							(mid -0.321484 0.511984)
							(end -0.381 0.3683)
						)
						(arc
							(start -0.381 -0.3683)
							(mid -0.321484 -0.511984)
							(end -0.1778 -0.5715)
						)
						(arc
							(start 0.1778 -0.5715)
							(mid 0.321484 -0.511984)
							(end 0.381 -0.3683)
						)
						(arc
							(start 0.381 0.3683)
							(mid 0.321484 0.511984)
							(end 0.1778 0.5715)
						)
					)
					(width 0)
					(fill yes)
				)
			)
		)
		(pad "G" smd custom
			(at -0.98425 0.9525 90)
			(size 0.1905 0.1905)
			(layers "F.Cu" "F.Mask" "F.Paste")
			(net "DRIVE_B_8_ACT")
			(options
				(clearance outline)
				(anchor circle)
			)
			(primitives
				(gr_poly
					(pts
						(arc
							(start -0.1778 0.5715)
							(mid -0.321484 0.511984)
							(end -0.381 0.3683)
						)
						(arc
							(start -0.381 -0.3683)
							(mid -0.321484 -0.511984)
							(end -0.1778 -0.5715)
						)
						(arc
							(start 0.1778 -0.5715)
							(mid 0.321484 -0.511984)
							(end 0.381 -0.3683)
						)
						(arc
							(start 0.381 0.3683)
							(mid 0.321484 0.511984)
							(end 0.1778 0.5715)
						)
					)
					(width 0)
					(fill yes)
				)
			)
		)
		(pad "S" smd custom
			(at 0.98425 0.9525 90)
			(size 0.1905 0.1905)
			(layers "F.Cu" "F.Mask" "F.Paste")
			(net "GND")
			(options
				(clearance outline)
				(anchor circle)
			)
			(primitives
				(gr_poly
					(pts
						(arc
							(start -0.1778 0.5715)
							(mid -0.321484 0.511984)
							(end -0.381 0.3683)
						)
						(arc
							(start -0.381 -0.3683)
							(mid -0.321484 -0.511984)
							(end -0.1778 -0.5715)
						)
						(arc
							(start 0.1778 -0.5715)
							(mid 0.321484 -0.511984)
							(end 0.381 -0.3683)
						)
						(arc
							(start 0.381 0.3683)
							(mid 0.321484 0.511984)
							(end 0.1778 0.5715)
						)
					)
					(width 0)
					(fill yes)
				)
			)
		)
	)
	(footprint ""
		(layer "F.Cu")
		(at 77.978 -255.524 90)
		(property "Reference" "C65"
			(at 0 0 90)
			(layer "F.SilkS")
			(hide yes)
			(effects
				(font
					(size 1.27 1.27)
				)
			)
		)
		(property "Value" "SCD033U25V2KX-GP"
			(at 1.1811 -2.7051 90)
			(unlocked yes)
			(layer "F.Fab")
			(hide yes)
			(effects
				(font
					(size 1.016 1.016)
					(thickness 0.1524)
				)
			)
		)
		(property "Device Type" "C402H22"
			(at 1.1811 -4.2291 90)
			(unlocked yes)
			(layer "F.Fab")
			(hide yes)
			(effects
				(font
					(size 1.016 1.016)
					(thickness 0.1524)
				)
			)
		)
		(duplicate_pad_numbers_are_jumpers no)
		(fp_rect
			(start -0.4318 0.9525)
			(end 0.4318 -0.9525)
			(stroke
				(width 0)
				(type default)
			)
			(fill no)
			(layer "F.CrtYd")
		)
		(fp_rect
			(start -0.4318 0.9525)
			(end 0.4318 -0.9525)
			(stroke
				(width 0)
				(type default)
			)
			(fill no)
			(layer "F.Fab")
		)
		(pad "1" smd custom
			(at 0 -0.4445 90)
			(size 0.1524 0.1524)
			(layers "F.Cu" "F.Mask" "F.Paste")
			(net "P12V_B")
			(options
				(clearance outline)
				(anchor circle)
			)
			(primitives
				(gr_poly
					(pts
						(arc
							(start 0.3048 -0.2032)
							(mid 0.275042 -0.275042)
							(end 0.2032 -0.3048)
						)
						(arc
							(start -0.2032 -0.3048)
							(mid -0.275042 -0.275042)
							(end -0.3048 -0.2032)
						)
						(arc
							(start -0.3048 0.2032)
							(mid -0.275042 0.275042)
							(end -0.2032 0.3048)
						)
						(arc
							(start 0.2032 0.3048)
							(mid 0.275042 0.275042)
							(end 0.3048 0.2032)
						)
					)
					(width 0)
					(fill yes)
				)
			)
		)
		(pad "2" smd custom
			(at 0 0.4445 90)
			(size 0.1524 0.1524)
			(layers "F.Cu" "F.Mask" "F.Paste")
			(net "SW_HDD_N2")
			(options
				(clearance outline)
				(anchor circle)
			)
			(primitives
				(gr_poly
					(pts
						(arc
							(start 0.3048 -0.2032)
							(mid 0.275042 -0.275042)
							(end 0.2032 -0.3048)
						)
						(arc
							(start -0.2032 -0.3048)
							(mid -0.275042 -0.275042)
							(end -0.3048 -0.2032)
						)
						(arc
							(start -0.3048 0.2032)
							(mid -0.275042 0.275042)
							(end -0.2032 0.3048)
						)
						(arc
							(start 0.2032 0.3048)
							(mid 0.275042 0.275042)
							(end 0.3048 0.2032)
						)
					)
					(width 0)
					(fill yes)
				)
			)
		)
	)
	(footprint ""
		(layer "F.Cu")
		(at 469.9 -140.462 90)
		(property "Reference" "C338"
			(at 0 0 90)
			(layer "F.SilkS")
			(hide yes)
			(effects
				(font
					(size 1.27 1.27)
				)
			)
		)
		(property "Value" "SCD033U25V2KX-GP"
			(at 1.1811 -2.7051 90)
			(unlocked yes)
			(layer "F.Fab")
			(hide yes)
			(effects
				(font
					(size 1.016 1.016)
					(thickness 0.1524)
				)
			)
		)
		(property "Device Type" "C402H22"
			(at 1.1811 -4.2291 90)
			(unlocked yes)
			(layer "F.Fab")
			(hide yes)
			(effects
				(font
					(size 1.016 1.016)
					(thickness 0.1524)
				)
			)
		)
		(duplicate_pad_numbers_are_jumpers no)
		(fp_rect
			(start -0.4318 0.9525)
			(end 0.4318 -0.9525)
			(stroke
				(width 0)
				(type default)
			)
			(fill no)
			(layer "F.CrtYd")
		)
		(fp_rect
			(start -0.4318 0.9525)
			(end 0.4318 -0.9525)
			(stroke
				(width 0)
				(type default)
			)
			(fill no)
			(layer "F.Fab")
		)
		(pad "1" smd custom
			(at 0 -0.4445 90)
			(size 0.1524 0.1524)
			(layers "F.Cu" "F.Mask" "F.Paste")
			(net "P12V_B")
			(options
				(clearance outline)
				(anchor circle)
			)
			(primitives
				(gr_poly
					(pts
						(arc
							(start 0.3048 -0.2032)
							(mid 0.275042 -0.275042)
							(end 0.2032 -0.3048)
						)
						(arc
							(start -0.2032 -0.3048)
							(mid -0.275042 -0.275042)
							(end -0.3048 -0.2032)
						)
						(arc
							(start -0.3048 0.2032)
							(mid -0.275042 0.275042)
							(end -0.2032 0.3048)
						)
						(arc
							(start 0.2032 0.3048)
							(mid 0.275042 0.275042)
							(end 0.3048 0.2032)
						)
					)
					(width 0)
					(fill yes)
				)
			)
		)
		(pad "2" smd custom
			(at 0 0.4445 90)
			(size 0.1524 0.1524)
			(layers "F.Cu" "F.Mask" "F.Paste")
			(net "SW_HDD_N23")
			(options
				(clearance outline)
				(anchor circle)
			)
			(primitives
				(gr_poly
					(pts
						(arc
							(start 0.3048 -0.2032)
							(mid 0.275042 -0.275042)
							(end 0.2032 -0.3048)
						)
						(arc
							(start -0.2032 -0.3048)
							(mid -0.275042 -0.275042)
							(end -0.3048 -0.2032)
						)
						(arc
							(start -0.3048 0.2032)
							(mid -0.275042 0.275042)
							(end -0.2032 0.3048)
						)
						(arc
							(start 0.2032 0.3048)
							(mid 0.275042 0.275042)
							(end 0.3048 0.2032)
						)
					)
					(width 0)
					(fill yes)
				)
			)
		)
	)
	(footprint ""
		(layer "F.Cu")
		(at 301.371 -230.1494 -90)
		(property "Reference" "R5"
			(at 0 0 270)
			(layer "F.SilkS")
			(hide yes)
			(effects
				(font
					(size 1.27 1.27)
				)
			)
		)
		(property "Value" "10KR2F-2-GP"
			(at 0.064008 -3.993896 270)
			(unlocked yes)
			(layer "F.Fab")
			(hide yes)
			(effects
				(font
					(size 1.016 1.016)
					(thickness 0.1524)
				)
			)
		)
		(property "Device Type" "R402H16"
			(at 0.064008 -5.517896 270)
			(unlocked yes)
			(layer "F.Fab")
			(hide yes)
			(effects
				(font
					(size 1.016 1.016)
					(thickness 0.1524)
				)
			)
		)
		(duplicate_pad_numbers_are_jumpers no)
		(fp_line
			(start -0.508 -0.9398)
			(end -0.508 0.9398)
			(stroke
				(width 0.1524)
				(type default)
			)
			(layer "F.SilkS")
		)
		(fp_line
			(start 0.508 -0.9398)
			(end -0.508 -0.9398)
			(stroke
				(width 0.1524)
				(type default)
			)
			(layer "F.SilkS")
		)
		(fp_rect
			(start -0.508 0.9398)
			(end 0.508 -0.9398)
			(stroke
				(width 0)
				(type default)
			)
			(fill no)
			(layer "F.CrtYd")
		)
		(fp_rect
			(start -0.508 0.9398)
			(end 0.508 -0.9398)
			(stroke
				(width 0)
				(type default)
			)
			(fill no)
			(layer "F.Fab")
		)
		(pad "1" smd custom
			(at 0 -0.4445 270)
			(size 0.1397 0.1397)
			(layers "F.Cu" "F.Mask" "F.Paste")
			(net "P3V3_STBY_B")
			(options
				(clearance outline)
				(anchor circle)
			)
			(primitives
				(gr_poly
					(pts
						(arc
							(start -0.1778 -0.2794)
							(mid -0.249642 -0.249642)
							(end -0.2794 -0.1778)
						)
						(arc
							(start -0.2794 0.1778)
							(mid -0.249642 0.249642)
							(end -0.1778 0.2794)
						)
						(arc
							(start 0.1778 0.2794)
							(mid 0.249642 0.249642)
							(end 0.2794 0.1778)
						)
						(arc
							(start 0.2794 -0.1778)
							(mid 0.249642 -0.249642)
							(end 0.1778 -0.2794)
						)
					)
					(width 0)
					(fill yes)
				)
			)
		)
		(pad "2" smd custom
			(at 0 0.4445 270)
			(size 0.1397 0.1397)
			(layers "F.Cu" "F.Mask" "F.Paste")
			(net "SCC_B_TYPE_1")
			(options
				(clearance outline)
				(anchor circle)
			)
			(primitives
				(gr_poly
					(pts
						(arc
							(start -0.1778 -0.2794)
							(mid -0.249642 -0.249642)
							(end -0.2794 -0.1778)
						)
						(arc
							(start -0.2794 0.1778)
							(mid -0.249642 0.249642)
							(end -0.1778 0.2794)
						)
						(arc
							(start 0.1778 0.2794)
							(mid 0.249642 0.249642)
							(end 0.2794 0.1778)
						)
						(arc
							(start 0.2794 -0.1778)
							(mid 0.249642 -0.249642)
							(end 0.1778 -0.2794)
						)
					)
					(width 0)
					(fill yes)
				)
			)
		)
	)
	(footprint ""
		(layer "F.Cu")
		(at 419.73754 -369.57)
		(property "Reference" "R955"
			(at 0 0 0)
			(layer "F.SilkS")
			(hide yes)
			(effects
				(font
					(size 1.27 1.27)
				)
			)
		)
		(property "Value" "0R2J-2-GP"
			(at 0.064008 -3.993896 0)
			(unlocked yes)
			(layer "F.Fab")
			(hide yes)
			(effects
				(font
					(size 1.016 1.016)
					(thickness 0.1524)
				)
			)
		)
		(property "Device Type" "R402H16"
			(at 0.064008 -5.517896 0)
			(unlocked yes)
			(layer "F.Fab")
			(hide yes)
			(effects
				(font
					(size 1.016 1.016)
					(thickness 0.1524)
				)
			)
		)
		(duplicate_pad_numbers_are_jumpers no)
		(fp_line
			(start -0.508 -0.9398)
			(end -0.508 0.9398)
			(stroke
				(width 0.1524)
				(type default)
			)
			(layer "F.SilkS")
		)
		(fp_line
			(start 0.508 -0.9398)
			(end -0.508 -0.9398)
			(stroke
				(width 0.1524)
				(type default)
			)
			(layer "F.SilkS")
		)
		(fp_rect
			(start -0.508 0.9398)
			(end 0.508 -0.9398)
			(stroke
				(width 0)
				(type default)
			)
			(fill no)
			(layer "F.CrtYd")
		)
		(fp_rect
			(start -0.508 0.9398)
			(end 0.508 -0.9398)
			(stroke
				(width 0)
				(type default)
			)
			(fill no)
			(layer "F.Fab")
		)
		(pad "1" smd custom
			(at 0 -0.4445)
			(size 0.1397 0.1397)
			(layers "F.Cu" "F.Mask" "F.Paste")
			(net "FAN_3_PWM")
			(options
				(clearance outline)
				(anchor circle)
			)
			(primitives
				(gr_poly
					(pts
						(arc
							(start -0.1778 -0.2794)
							(mid -0.249642 -0.249642)
							(end -0.2794 -0.1778)
						)
						(arc
							(start -0.2794 0.1778)
							(mid -0.249642 0.249642)
							(end -0.1778 0.2794)
						)
						(arc
							(start 0.1778 0.2794)
							(mid 0.249642 0.249642)
							(end 0.2794 0.1778)
						)
						(arc
							(start 0.2794 -0.1778)
							(mid 0.249642 -0.249642)
							(end 0.1778 -0.2794)
						)
					)
					(width 0)
					(fill yes)
				)
			)
		)
		(pad "2" smd custom
			(at 0 0.4445)
			(size 0.1397 0.1397)
			(layers "F.Cu" "F.Mask" "F.Paste")
			(net "PWM_OUT_FAN3")
			(options
				(clearance outline)
				(anchor circle)
			)
			(primitives
				(gr_poly
					(pts
						(arc
							(start -0.1778 -0.2794)
							(mid -0.249642 -0.249642)
							(end -0.2794 -0.1778)
						)
						(arc
							(start -0.2794 0.1778)
							(mid -0.249642 0.249642)
							(end -0.1778 0.2794)
						)
						(arc
							(start 0.1778 0.2794)
							(mid 0.249642 0.249642)
							(end 0.2794 0.1778)
						)
						(arc
							(start 0.2794 -0.1778)
							(mid 0.249642 -0.249642)
							(end 0.1778 -0.2794)
						)
					)
					(width 0)
					(fill yes)
				)
			)
		)
	)
)
